FILE_TYPE = CONNECTIVITY;
{Allegro Design Entry HDL 17.4-2019 S026 (4007227) 1/17/2022}
"PAGE_NUMBER" = 103;
0"NC";
1"GND\g";
2"GND\g";
3"P3V3\g";
4"P3V3\g";
5"P3V3_AUX\g";
6"M_G_CPU1_SA_CB<7:0>";
7"M_G_CPU1_SA_CA<6:0>";
8"M_G_CPU1_SB_DQS_DP<9:0>";
9"M_G_CPU1_SB_DQS_DN<9:0>";
10"M_G_CPU1_SA_DQS_DP<9:0>";
11"M_G_CPU1_SA_DQS_DN<9:0>";
12"M_G_CPU1_SB_DQ<31:0>";
13"M_G_CPU1_SA_DQ<31:0>";
14"M_G_CPU1_SB_CB<7:0>";
15"M_G_CPU1_SB_CA<6:0>";
16"M_G_CPU1_ALERT_N";
17"I3C_SPD_DDRG_CPU1_SDA";
18"P3V3_AUX\g";
19"PD_CHG_CPU1_DIMM0_SAA";
20"M_G_CPU1_RESET_N";
21"PWRGD_CHG_CPU1_DIMM0";
22"M_G_CPU1_SB_CB<0>";
23"M_G_CPU1_SB_CB<1>";
24"I3C_SPD_DDRG_CPU1_SCL";
25"M_G_CPU1_SB_CB<6>";
26"M_G_CPU1_SB_DQ<15>";
27"M_G_CPU1_SB_DQ<14>";
28"PWRGD_CHGL_CPU1_R1";
29"PWRGD_CHGL_CPU1";
30"PD_CHG_CPU1_DIMM0_SAA";
31"PWRGD_CHGL_CPU1";
32"P3V3_AUX\g";
33"P3V3_AUX\g";
34"P12V_MEM_CPU1\g";
35"GND\g";
36"GND\g";
37"GND\g";
38"PWRGD_CHGL_CPU1_R2";
39"M_G_CPU1_SA_DQ<31>";
40"M_G_CPU1_SA_CB<4>";
41"M_G_CPU1_SA_CB<1>";
42"M_G_CPU1_SB_CB<7>";
43"M_G_CPU1_SB_CA<0>";
44"M_G_CPU1_SB_CA<1>";
45"M_G_CPU1_SB_CA<2>";
46"M_G_CPU1_SB_CA<3>";
47"M_G_CPU1_SA_CA<4>";
48"M_G_CPU1_SB_CA<4>";
49"M_G_CPU1_SA_CA<5>";
50"M_G_CPU1_SB_CA<5>";
51"M_G_CPU1_SA_CA<6>";
52"M_G_CPU1_SB_CA<6>";
53"M_G_CPU1_SA_CB<6>";
54"M_G_CPU1_SA_CB<5>";
55"M_G_CPU1_SA_CB<3>";
56"M_G_CPU1_SA_CB<2>";
57"M_G_CPU1_SA_CB<0>";
58"M_G_CPU1_SB_CB<5>";
59"M_G_CPU1_SB_CB<4>";
60"M_G_CPU1_SB_CB<3>";
61"M_G_CPU1_SB_CB<2>";
62"M_G_CPU1_CLK_DN<0>";
63"M_G_CPU1_CLK_DP<0>";
64"M_G_CPU1_SA_CS_N<0>";
65"M_G_CPU1_SB_CS_N<0>";
66"M_G_CPU1_SA_CS_N<1>";
67"M_G_CPU1_SB_CS_N<1>";
68"M_G_CPU1_SA_DQ<30>";
69"M_G_CPU1_SA_DQ<29>";
70"M_G_CPU1_SA_DQ<28>";
71"M_G_CPU1_SA_DQ<27>";
72"M_G_CPU1_SA_DQ<26>";
73"M_G_CPU1_SA_DQ<25>";
74"M_G_CPU1_SA_DQ<24>";
75"M_G_CPU1_SA_DQ<23>";
76"M_G_CPU1_SA_DQ<22>";
77"M_G_CPU1_SA_DQ<21>";
78"M_G_CPU1_SA_DQ<20>";
79"M_G_CPU1_SA_DQ<19>";
80"M_G_CPU1_SA_DQ<18>";
81"M_G_CPU1_SA_DQ<17>";
82"M_G_CPU1_SA_DQ<16>";
83"M_G_CPU1_SA_DQ<15>";
84"M_G_CPU1_SA_DQ<14>";
85"M_G_CPU1_SA_DQ<13>";
86"M_G_CPU1_SA_DQ<12>";
87"M_G_CPU1_SA_DQ<11>";
88"M_G_CPU1_SA_DQ<10>";
89"M_G_CPU1_SA_DQ<9>";
90"M_G_CPU1_SA_DQ<8>";
91"M_G_CPU1_SA_DQ<7>";
92"M_G_CPU1_SA_DQ<6>";
93"M_G_CPU1_SA_DQ<5>";
94"M_G_CPU1_SA_DQ<4>";
95"M_G_CPU1_SA_DQ<3>";
96"M_G_CPU1_SA_DQ<2>";
97"M_G_CPU1_SA_DQ<1>";
98"M_G_CPU1_SA_DQ<0>";
99"M_G_CPU1_SB_DQ<31>";
100"M_G_CPU1_SB_DQ<30>";
101"M_G_CPU1_SB_DQ<29>";
102"M_G_CPU1_SB_DQ<28>";
103"M_G_CPU1_SB_DQ<27>";
104"M_G_CPU1_SB_DQ<26>";
105"M_G_CPU1_SB_DQ<25>";
106"M_G_CPU1_SB_DQ<24>";
107"M_G_CPU1_SB_DQ<23>";
108"M_G_CPU1_SB_DQ<22>";
109"M_G_CPU1_SB_DQ<21>";
110"M_G_CPU1_SB_DQ<20>";
111"M_G_CPU1_SB_DQ<19>";
112"M_G_CPU1_SB_DQ<18>";
113"M_G_CPU1_SB_DQ<17>";
114"M_G_CPU1_SB_DQ<16>";
115"M_G_CPU1_SB_DQ<13>";
116"M_G_CPU1_SB_DQ<12>";
117"M_G_CPU1_SB_DQ<11>";
118"M_G_CPU1_SB_DQ<10>";
119"M_G_CPU1_SB_DQ<9>";
120"M_G_CPU1_SB_DQ<8>";
121"M_G_CPU1_SB_DQ<7>";
122"M_G_CPU1_SB_DQ<6>";
123"M_G_CPU1_SB_DQ<5>";
124"M_G_CPU1_SB_DQ<4>";
125"M_G_CPU1_SB_DQ<3>";
126"M_G_CPU1_SB_DQ<2>";
127"M_G_CPU1_SB_DQ<1>";
128"M_G_CPU1_SB_DQ<0>";
129"M_G_CPU1_SA_RSP<0>";
130"M_G_CPU1_SB_RSP<0>";
131"M_G_CPU1_SA_PAR";
132"M_G_CPU1_SB_PAR";
133"M_G_CPU1_SA_DQS_DN<7>";
134"M_G_CPU1_SA_DQS_DP<6>";
135"M_G_CPU1_SB_DQS_DP<8>";
136"M_G_CPU1_SB_DQS_DN<8>";
137"M_G_CPU1_SB_DQS_DP<7>";
138"M_G_CPU1_SA_DQS_DN<0>";
139"M_G_CPU1_SA_DQS_DP<0>";
140"M_G_CPU1_SB_DQS_DN<0>";
141"M_G_CPU1_SB_DQS_DP<0>";
142"M_G_CPU1_SA_DQS_DN<1>";
143"M_G_CPU1_SA_DQS_DP<1>";
144"M_G_CPU1_SB_DQS_DN<1>";
145"M_G_CPU1_SB_DQS_DP<1>";
146"M_G_CPU1_SA_DQS_DN<2>";
147"M_G_CPU1_SA_DQS_DP<2>";
148"M_G_CPU1_SB_DQS_DN<2>";
149"M_G_CPU1_SB_DQS_DP<2>";
150"M_G_CPU1_SA_DQS_DN<3>";
151"M_G_CPU1_SA_DQS_DP<3>";
152"M_G_CPU1_SB_DQS_DN<3>";
153"M_G_CPU1_SB_DQS_DP<3>";
154"M_G_CPU1_SA_DQS_DN<4>";
155"M_G_CPU1_SA_DQS_DP<4>";
156"M_G_CPU1_SB_DQS_DN<4>";
157"M_G_CPU1_SB_DQS_DP<4>";
158"M_G_CPU1_SA_DQS_DN<5>";
159"M_G_CPU1_SA_DQS_DP<5>";
160"M_G_CPU1_SB_DQS_DN<5>";
161"M_G_CPU1_SB_DQS_DP<5>";
162"M_G_CPU1_SA_DQS_DN<6>";
163"M_G_CPU1_SB_DQS_DN<6>";
164"M_G_CPU1_SB_DQS_DP<6>";
165"M_G_CPU1_SA_DQS_DP<7>";
166"M_G_CPU1_SB_DQS_DN<7>";
167"M_G_CPU1_SA_DQS_DN<8>";
168"M_G_CPU1_SA_DQS_DP<8>";
169"M_G_CPU1_SA_DQS_DN<9>";
170"M_G_CPU1_SA_DQS_DP<9>";
171"M_G_CPU1_SB_DQS_DN<9>";
172"M_G_CPU1_SB_DQS_DP<9>";
173"M_G_CPU1_SA_CA<0>";
174"M_G_CPU1_SA_CA<1>";
175"M_G_CPU1_SA_CA<2>";
176"M_G_CPU1_SA_CA<3>";
177"M_G_CPU1_SA_CB<7>";
178"PWRGD_CHGL_CPU1";
179"I3C_SPD_DDRGL_CPU1_SDA";
180"I3C_SPD_DDRGL_CPU1_SCL";
%"TAP"
"1","(-5775,4100)","0","mstr_standard","I100";
;
CDS_LIB"mstr_standard"
BODY_TYPE"PLUMBING"
HDL_TAP"TRUE";
"B \NAC \NWC"13;
"S \NAC"
BN"6"92;
%"TAP"
"1","(-5775,4250)","0","mstr_standard","I101";
;
CDS_LIB"mstr_standard"
BODY_TYPE"PLUMBING"
HDL_TAP"TRUE";
"B \NAC \NWC"13;
"S \NAC"
BN"9"89;
%"TAP"
"1","(-5775,4200)","0","mstr_standard","I102";
;
CDS_LIB"mstr_standard"
BODY_TYPE"PLUMBING"
HDL_TAP"TRUE";
"B \NAC \NWC"13;
"S \NAC"
BN"8"90;
%"TAP"
"1","(-5775,4050)","0","mstr_standard","I103";
;
CDS_LIB"mstr_standard"
BODY_TYPE"PLUMBING"
HDL_TAP"TRUE";
"B \NAC \NWC"13;
"S \NAC"
BN"5"93;
%"TAP"
"1","(-5775,4450)","0","mstr_standard","I104";
;
CDS_LIB"mstr_standard"
BODY_TYPE"PLUMBING"
HDL_TAP"TRUE";
"B \NAC \NWC"13;
"S \NAC"
BN"13"85;
%"TAP"
"1","(-5775,4500)","0","mstr_standard","I105";
;
CDS_LIB"mstr_standard"
BODY_TYPE"PLUMBING"
HDL_TAP"TRUE";
"B \NAC \NWC"13;
"S \NAC"
BN"14"84;
%"TAP"
"1","(-5775,4300)","0","mstr_standard","I106";
;
CDS_LIB"mstr_standard"
BODY_TYPE"PLUMBING"
HDL_TAP"TRUE";
"B \NAC \NWC"13;
"S \NAC"
BN"10"88;
%"TAP"
"1","(-5775,4350)","0","mstr_standard","I107";
;
CDS_LIB"mstr_standard"
BODY_TYPE"PLUMBING"
HDL_TAP"TRUE";
"B \NAC \NWC"13;
"S \NAC"
BN"11"87;
%"TAP"
"1","(-5775,4400)","0","mstr_standard","I108";
;
CDS_LIB"mstr_standard"
BODY_TYPE"PLUMBING"
HDL_TAP"TRUE";
"B \NAC \NWC"13;
"S \NAC"
BN"12"86;
%"TAP"
"1","(-5775,4700)","0","mstr_standard","I109";
;
CDS_LIB"mstr_standard"
BODY_TYPE"PLUMBING"
HDL_TAP"TRUE";
"B \NAC \NWC"13;
"S \NAC"
BN"18"80;
%"TAP"
"1","(-5775,4750)","0","mstr_standard","I110";
;
CDS_LIB"mstr_standard"
BODY_TYPE"PLUMBING"
HDL_TAP"TRUE";
"B \NAC \NWC"13;
"S \NAC"
BN"19"79;
%"TAP"
"1","(-5775,4550)","0","mstr_standard","I111";
;
CDS_LIB"mstr_standard"
BODY_TYPE"PLUMBING"
HDL_TAP"TRUE";
"B \NAC \NWC"13;
"S \NAC"
BN"15"83;
%"TAP"
"1","(-5775,4600)","0","mstr_standard","I112";
;
CDS_LIB"mstr_standard"
BODY_TYPE"PLUMBING"
HDL_TAP"TRUE";
"B \NAC \NWC"13;
"S \NAC"
BN"16"82;
%"TAP"
"1","(-5775,4650)","0","mstr_standard","I113";
;
CDS_LIB"mstr_standard"
BODY_TYPE"PLUMBING"
HDL_TAP"TRUE";
"B \NAC \NWC"13;
"S \NAC"
BN"17"81;
%"TAP"
"1","(-5775,5000)","0","mstr_standard","I114";
;
CDS_LIB"mstr_standard"
BODY_TYPE"PLUMBING"
HDL_TAP"TRUE";
"B \NAC \NWC"13;
"S \NAC"
BN"24"74;
%"TAP"
"1","(-5775,4950)","0","mstr_standard","I115";
;
CDS_LIB"mstr_standard"
BODY_TYPE"PLUMBING"
HDL_TAP"TRUE";
"B \NAC \NWC"13;
"S \NAC"
BN"23"75;
%"TAP"
"1","(-5775,5050)","0","mstr_standard","I116";
;
CDS_LIB"mstr_standard"
BODY_TYPE"PLUMBING"
HDL_TAP"TRUE";
"B \NAC \NWC"13;
"S \NAC"
BN"25"73;
%"TAP"
"1","(-5775,4800)","0","mstr_standard","I117";
;
CDS_LIB"mstr_standard"
BODY_TYPE"PLUMBING"
HDL_TAP"TRUE";
"B \NAC \NWC"13;
"S \NAC"
BN"20"78;
%"TAP"
"1","(-5775,4850)","0","mstr_standard","I118";
;
CDS_LIB"mstr_standard"
BODY_TYPE"PLUMBING"
HDL_TAP"TRUE";
"B \NAC \NWC"13;
"S \NAC"
BN"21"77;
%"TAP"
"1","(-5775,4900)","0","mstr_standard","I119";
;
CDS_LIB"mstr_standard"
BODY_TYPE"PLUMBING"
HDL_TAP"TRUE";
"B \NAC \NWC"13;
"S \NAC"
BN"22"76;
%"TAP"
"1","(-5775,5300)","0","mstr_standard","I120";
;
CDS_LIB"mstr_standard"
BODY_TYPE"PLUMBING"
HDL_TAP"TRUE";
"B \NAC \NWC"13;
"S \NAC"
BN"30"68;
%"TAP"
"1","(-5775,5200)","0","mstr_standard","I121";
;
CDS_LIB"mstr_standard"
BODY_TYPE"PLUMBING"
HDL_TAP"TRUE";
"B \NAC \NWC"13;
"S \NAC"
BN"28"70;
%"TAP"
"1","(-5775,5250)","0","mstr_standard","I122";
;
CDS_LIB"mstr_standard"
BODY_TYPE"PLUMBING"
HDL_TAP"TRUE";
"B \NAC \NWC"13;
"S \NAC"
BN"29"69;
%"TAP"
"1","(-5775,5150)","0","mstr_standard","I123";
;
CDS_LIB"mstr_standard"
BODY_TYPE"PLUMBING"
HDL_TAP"TRUE";
"B \NAC \NWC"13;
"S \NAC"
BN"27"71;
%"TAP"
"1","(-5775,5100)","0","mstr_standard","I124";
;
CDS_LIB"mstr_standard"
BODY_TYPE"PLUMBING"
HDL_TAP"TRUE";
"B \NAC \NWC"13;
"S \NAC"
BN"26"72;
%"TAP"
"1","(-5775,5350)","0","mstr_standard","I125";
;
CDS_LIB"mstr_standard"
BODY_TYPE"PLUMBING"
HDL_TAP"TRUE";
"B \NAC \NWC"13;
"S \NAC"
BN"31"39;
%"GND"
"1","(-6200,900)","0","mstr_symbols","I128";
;
VOLTAGE"0.0"
CDS_LIB"mstr_symbols"
BOM_COST"MEM"
SIZE"1B"
BODY_TYPE"PLUMBING"
HDL_POWER"GND";
"A\NAC"1;
%"Q_RES"
"2","(-6200,1125)","0","pure_quanta","I129";
;
LOCATION"R37"
SEC"1"
VALUE"10K"
TOLERANCE"1%"
PACK_TYPE"0402LF"
MATERIAL"CHIP"
WATTAGE"1/16W"
SEC_TYPE"0402LF"
CDS_LIB"pure_quanta"
BOM_COST"MEM"
PART_NUMBER"CS31002FB08";
"A"
$PN"1"
XNET_PINS"3"30;
"B"
$PN"2"
XNET_PINS"2"1;
%"GND"
"1","(-2125,1875)","0","mstr_symbols","I140";
;
VOLTAGE"0.0"
SIZE"1B"
CDS_LIB"mstr_symbols"
BODY_TYPE"PLUMBING"
HDL_POWER"GND";
"A\NAC"37;
%"GND"
"1","(-525,1675)","0","mstr_symbols","I141";
;
VOLTAGE"0.0"
SIZE"1B"
CDS_LIB"mstr_symbols"
BODY_TYPE"PLUMBING"
HDL_POWER"GND";
"A\NAC"36;
%"SCONN288_DDR506112002KQ"
"3","(-1325,3625)","0","pure_quanta","I142";
;
LOCATION"J102"
$SEC"3"
CDS_SEC"3"
VALUE"SCONN288_DDR506112002KQ"
MATERIAL"IO"
PART_TYPE"SMLF"
CDS_LIB"pure_quanta"
NEEDS_NO_SIZE"TRUE"
CDS_LMAN_SYM_OUTLINE"-450,1800,450,-1750"
PART_NUMBER"DFHST8FS479";
"G3"
$PN"G3"36;
"G2"
$PN"G2"36;
"G1"
$PN"G1"36;
"VSS62"
$PN"141"36;
"VSS61"
$PN"139"36;
"VSS60"
$PN"136"36;
"VSS58"
$PN"132"36;
"VSS104"
$PN"240"37;
"VSS102"
$PN"235"37;
"VSS100"
$PN"230"37;
"VIN_BULK2"
$PN"146"34;
"VIN_BULK1"
$PN"145"34;
"VIN_BULK0"
$PN"1"34;
"VSS126"
$PN"288"37;
"VSS125"
$PN"286"37;
"VSS124"
$PN"284"37;
"VSS123"
$PN"281"37;
"VSS122"
$PN"279"37;
"VSS121"
$PN"277"37;
"VSS120"
$PN"275"37;
"VSS119"
$PN"273"37;
"VSS118"
$PN"270"37;
"VSS117"
$PN"268"37;
"VSS116"
$PN"266"37;
"VSS115"
$PN"264"37;
"VSS114"
$PN"262"37;
"VSS113"
$PN"259"37;
"VSS112"
$PN"257"37;
"VSS111"
$PN"255"37;
"VSS110"
$PN"253"37;
"VSS109"
$PN"251"37;
"VSS108"
$PN"248"37;
"VSS107"
$PN"246"37;
"VSS106"
$PN"244"37;
"VSS105"
$PN"242"37;
"VSS103"
$PN"237"37;
"VSS101"
$PN"233"37;
"VSS99"
$PN"228"37;
"VSS98"
$PN"226"37;
"VSS97"
$PN"224"37;
"VSS96"
$PN"222"37;
"VSS95"
$PN"219"37;
"VSS94"
$PN"216"37;
"VSS93"
$PN"214"37;
"VSS92"
$PN"212"37;
"VSS91"
$PN"210"37;
"VSS90"
$PN"208"37;
"VSS89"
$PN"206"37;
"VSS88"
$PN"204"37;
"VSS87"
$PN"202"37;
"VSS86"
$PN"199"37;
"VSS85"
$PN"197"37;
"VSS84"
$PN"195"37;
"VSS83"
$PN"193"37;
"VSS82"
$PN"191"37;
"VSS81"
$PN"188"37;
"VSS80"
$PN"186"37;
"VSS79"
$PN"184"37;
"VSS78"
$PN"182"37;
"VSS77"
$PN"180"37;
"VSS76"
$PN"177"37;
"VSS75"
$PN"175"37;
"VSS74"
$PN"173"37;
"VSS73"
$PN"171"37;
"VSS72"
$PN"169"37;
"VSS71"
$PN"166"37;
"VSS70"
$PN"164"37;
"VSS69"
$PN"162"37;
"VSS68"
$PN"160"37;
"VSS67"
$PN"158"37;
"VSS66"
$PN"155"37;
"VSS65"
$PN"153"37;
"VSS64"
$PN"151"37;
"VSS63"
$PN"143"36;
"VSS59"
$PN"134"36;
"VSS57"
$PN"130"36;
"VSS56"
$PN"128"36;
"VSS55"
$PN"125"36;
"VSS54"
$PN"123"36;
"VSS53"
$PN"121"36;
"VSS52"
$PN"119"36;
"VSS51"
$PN"117"36;
"VSS50"
$PN"114"36;
"VSS49"
$PN"112"36;
"VSS48"
$PN"110"36;
"VSS47"
$PN"108"36;
"VSS46"
$PN"106"36;
"VSS45"
$PN"103"36;
"VSS44"
$PN"101"36;
"VSS43"
$PN"99"36;
"VSS42"
$PN"97"36;
"VSS41"
$PN"95"36;
"VSS40"
$PN"92"36;
"VSS39"
$PN"90"36;
"VSS38"
$PN"88"36;
"VSS37"
$PN"85"36;
"VSS36"
$PN"83"36;
"VSS35"
$PN"81"36;
"VSS34"
$PN"79"36;
"VSS33"
$PN"77"36;
"VSS32"
$PN"75"36;
"VSS31"
$PN"73"36;
"VSS30"
$PN"71"36;
"VSS29"
$PN"69"36;
"VSS28"
$PN"67"36;
"VSS27"
$PN"65"36;
"VSS26"
$PN"63"36;
"VSS25"
$PN"61"36;
"VSS24"
$PN"59"36;
"VSS23"
$PN"57"36;
"VSS22"
$PN"54"36;
"VSS21"
$PN"52"36;
"VSS20"
$PN"50"36;
"VSS19"
$PN"48"36;
"VSS18"
$PN"46"36;
"VSS17"
$PN"43"36;
"VSS16"
$PN"41"36;
"VSS15"
$PN"39"36;
"VSS14"
$PN"37"36;
"VSS13"
$PN"35"36;
"VSS12"
$PN"32"36;
"VSS11"
$PN"30"36;
"VSS10"
$PN"28"36;
"VSS9"
$PN"26"36;
"VSS8"
$PN"24"36;
"VSS7"
$PN"21"36;
"VSS6"
$PN"19"36;
"VSS5"
$PN"17"36;
"VSS4"
$PN"15"36;
"VSS3"
$PN"13"36;
"VSS2"
$PN"10"36;
"VSS1"
$PN"8"36;
"VSS0"
$PN"6"36;
%"Q_CAP"
"1","(-8675,3200)","2","pure_quanta","I185";
;
LOCATION"C160"
$SEC"1"
CDS_SEC"1"
PACK_TYPE"0402"
MATERIAL"X7R"
TOLERANCE"10%"
VOLTAGE"25V"
VALUE"0.1UF"
BOM_COST"MEM"
CDS_LIB"pure_quanta"
ROOM""
PART_NUMBER"CH4104K1B00";
"B"
$PN"2"2;
"A"
$PN"1"18;
%"GND"
"1","(-8675,2975)","0","mstr_symbols","I186";
;
ROOM"MEM_EFGH_DECOUPLING_CAPS"
VOLTAGE"0"
CDS_LIB"mstr_symbols"
SIZE"1B"
BOM_COST"MEM"
BODY_TYPE"PLUMBING"
HDL_POWER"GND";
"A\NAC"2;
%"Q_RES"
"1","(-8400,2100)","2","pure_quanta","I188";
;
LOCATION"R1184"
$SEC"1"
CDS_SEC"1"
VALUE"1K"
PACK_TYPE"0402LF"
MATERIAL"CHIP"
WATTAGE"1/16W"
BOM_COST"MEM"
CDS_LIB"pure_quanta"
TOLERANCE"1%"
ROOM""
PART_NUMBER"CS21002FB06";
"B"
$PN"2"178;
"A"
$PN"1"21;
%"Q_RES"
"2","(-8525,2250)","2","pure_quanta","I189";
;
LOCATION"R109"
$SEC"1"
CDS_SEC"1"
PACK_TYPE"0402LF"
VALUE"1K"
TOLERANCE"1%"
WATTAGE"1/16W"
MATERIAL"EMPTY"
CDS_LIB"pure_quanta"
BOM_COST"MEM"
ROOM""
PART_NUMBER"CS21002FB06";
"A"
$PN"1"3;
"B"
$PN"2"178;
%"VCC_CORE"
"1","(-8525,2425)","0","mstr_symbols","I190";
;
HDL_POWER"P3V3"
ROOM"PVCCINFAON_CPU0_CTRL"
VOLTAGE"3.3"
CDS_LIB"mstr_symbols";
"A"3;
%"VCC_CORE"
"1","(-8275,2425)","0","mstr_symbols","I191";
;
HDL_POWER"P3V3"
ROOM"PVCCINFAON_CPU0_CTRL"
VOLTAGE"3.3"
CDS_LIB"mstr_symbols";
"A"4;
%"Q_RES"
"2","(-8275,2250)","0","pure_quanta","I192";
;
LOCATION"R110"
$SEC"1"
CDS_SEC"1"
VALUE"1K"
WATTAGE"1/16W"
MATERIAL"EMPTY"
PACK_TYPE"0402LF"
TOLERANCE"1%"
BOM_COST"MEM"
CDS_LIB"pure_quanta"
ROOM""
PART_NUMBER"CS21002FB06";
"A"
$PN"1"4;
"B"
$PN"2"21;
%"TAP"
"1","(-3050,4375)","0","mstr_standard","I198";
;
CDS_LIB"mstr_standard"
BODY_TYPE"PLUMBING"
HDL_TAP"TRUE";
"B \NAC \NWC"11;
"S \NAC"
BN"9"169;
%"TAP"
"1","(-3050,4275)","0","mstr_standard","I199";
;
CDS_LIB"mstr_standard"
BODY_TYPE"PLUMBING"
HDL_TAP"TRUE";
"B \NAC \NWC"11;
"S \NAC"
BN"8"167;
%"TAP"
"1","(-3250,4425)","0","mstr_standard","I200";
;
CDS_LIB"mstr_standard"
BODY_TYPE"PLUMBING"
HDL_TAP"TRUE";
"B \NAC \NWC"10;
"S \NAC"
BN"9"170;
%"TAP"
"1","(-3250,4325)","0","mstr_standard","I201";
;
CDS_LIB"mstr_standard"
BODY_TYPE"PLUMBING"
HDL_TAP"TRUE";
"B \NAC \NWC"10;
"S \NAC"
BN"8"168;
%"TAP"
"1","(-3050,4175)","0","mstr_standard","I202";
;
CDS_LIB"mstr_standard"
BODY_TYPE"PLUMBING"
HDL_TAP"TRUE";
"B \NAC \NWC"11;
"S \NAC"
BN"7"133;
%"TAP"
"1","(-3050,4075)","0","mstr_standard","I203";
;
CDS_LIB"mstr_standard"
BODY_TYPE"PLUMBING"
HDL_TAP"TRUE";
"B \NAC \NWC"11;
"S \NAC"
BN"6"162;
%"TAP"
"1","(-3050,3875)","0","mstr_standard","I204";
;
CDS_LIB"mstr_standard"
BODY_TYPE"PLUMBING"
HDL_TAP"TRUE";
"B \NAC \NWC"11;
"S \NAC"
BN"4"154;
%"TAP"
"1","(-3050,3975)","0","mstr_standard","I205";
;
CDS_LIB"mstr_standard"
BODY_TYPE"PLUMBING"
HDL_TAP"TRUE";
"B \NAC \NWC"11;
"S \NAC"
BN"5"158;
%"TAP"
"1","(-3050,3775)","0","mstr_standard","I206";
;
CDS_LIB"mstr_standard"
BODY_TYPE"PLUMBING"
HDL_TAP"TRUE";
"B \NAC \NWC"11;
"S \NAC"
BN"3"150;
%"TAP"
"1","(-3250,4225)","0","mstr_standard","I207";
;
CDS_LIB"mstr_standard"
BODY_TYPE"PLUMBING"
HDL_TAP"TRUE";
"B \NAC \NWC"10;
"S \NAC"
BN"7"165;
%"TAP"
"1","(-3250,4125)","0","mstr_standard","I208";
;
CDS_LIB"mstr_standard"
BODY_TYPE"PLUMBING"
HDL_TAP"TRUE";
"B \NAC \NWC"10;
"S \NAC"
BN"6"134;
%"TAP"
"1","(-3250,4025)","0","mstr_standard","I209";
;
CDS_LIB"mstr_standard"
BODY_TYPE"PLUMBING"
HDL_TAP"TRUE";
"B \NAC \NWC"10;
"S \NAC"
BN"5"159;
%"TAP"
"1","(-3250,3925)","0","mstr_standard","I210";
;
CDS_LIB"mstr_standard"
BODY_TYPE"PLUMBING"
HDL_TAP"TRUE";
"B \NAC \NWC"10;
"S \NAC"
BN"4"155;
%"TAP"
"1","(-3250,3825)","0","mstr_standard","I211";
;
CDS_LIB"mstr_standard"
BODY_TYPE"PLUMBING"
HDL_TAP"TRUE";
"B \NAC \NWC"10;
"S \NAC"
BN"3"151;
%"TAP"
"1","(-3050,3675)","0","mstr_standard","I212";
;
CDS_LIB"mstr_standard"
BODY_TYPE"PLUMBING"
HDL_TAP"TRUE";
"B \NAC \NWC"11;
"S \NAC"
BN"2"146;
%"TAP"
"1","(-3050,3575)","0","mstr_standard","I213";
;
CDS_LIB"mstr_standard"
BODY_TYPE"PLUMBING"
HDL_TAP"TRUE";
"B \NAC \NWC"11;
"S \NAC"
BN"1"142;
%"TAP"
"1","(-3050,3475)","0","mstr_standard","I214";
;
CDS_LIB"mstr_standard"
BODY_TYPE"PLUMBING"
HDL_TAP"TRUE";
"B \NAC \NWC"11;
"S \NAC"
BN"0"138;
%"TAP"
"1","(-3050,3325)","0","mstr_standard","I215";
;
CDS_LIB"mstr_standard"
BODY_TYPE"PLUMBING"
HDL_TAP"TRUE";
"B \NAC \NWC"9;
"S \NAC"
BN"9"171;
%"TAP"
"1","(-3050,3225)","0","mstr_standard","I216";
;
CDS_LIB"mstr_standard"
BODY_TYPE"PLUMBING"
HDL_TAP"TRUE";
"B \NAC \NWC"9;
"S \NAC"
BN"8"136;
%"TAP"
"1","(-3250,3725)","0","mstr_standard","I217";
;
CDS_LIB"mstr_standard"
BODY_TYPE"PLUMBING"
HDL_TAP"TRUE";
"B \NAC \NWC"10;
"S \NAC"
BN"2"147;
%"TAP"
"1","(-3250,3625)","0","mstr_standard","I218";
;
CDS_LIB"mstr_standard"
BODY_TYPE"PLUMBING"
HDL_TAP"TRUE";
"B \NAC \NWC"10;
"S \NAC"
BN"1"143;
%"TAP"
"1","(-3250,3525)","0","mstr_standard","I219";
;
CDS_LIB"mstr_standard"
BODY_TYPE"PLUMBING"
HDL_TAP"TRUE";
"B \NAC \NWC"10;
"S \NAC"
BN"0"139;
%"SCONN288_DDR506112002KQ"
"1","(-6625,3600)","0","pure_quanta","I22";
;
LOCATION"J102"
$SEC"1"
CDS_SEC"1"
MATERIAL"IO"
PART_TYPE"SMLF"
VALUE"SCONN288_DDR506112002KQ"
CDS_LIB"pure_quanta"
NEEDS_NO_SIZE"TRUE"
CDS_LMAN_SYM_OUTLINE"-450,1900,450,-1850"
PART_NUMBER"DFHST8FS479";
"PWR_GOOD||FAIL_N"
$PN"147"21;
"DQ31_A"
$PN"194"39;
"CB7_A"
$PN"205"177;
"CB4_A"
$PN"58"40;
"CB1_A"
$PN"53"41;
"CB7_B"
$PN"236"42;
"ALERT_N \B"
$PN"62"16;
"CA0_A"
$PN"66"173;
"CA0_B"
$PN"76"43;
"CA1_A"
$PN"211"174;
"CA1_B"
$PN"221"44;
"CA2_A"
$PN"68"175;
"CA2_B"
$PN"78"45;
"CA3_A"
$PN"213"176;
"CA3_B"
$PN"223"46;
"CA4_A"
$PN"70"47;
"CA4_B"
$PN"80"48;
"CA5_A"
$PN"215"49;
"CA5_B"
$PN"225"50;
"CA6_A"
$PN"72"51;
"CA6_B"
$PN"82"52;
"CB6_A"
$PN"203"53;
"CB5_A"
$PN"60"54;
"CB3_A"
$PN"198"55;
"CB2_A"
$PN"196"56;
"CB0_A"
$PN"51"57;
"CB6_B"
$PN"234"25;
"CB5_B"
$PN"91"58;
"CB4_B"
$PN"89"59;
"CB3_B"
$PN"243"60;
"CB2_B"
$PN"241"61;
"CB1_B"
$PN"98"23;
"CB0_B"
$PN"96"22;
"CK_C \B"
$PN"218"62;
"CK_T"
$PN"217"63;
"CS0_A_N"
$PN"64"64;
"CS0_B_N"
$PN"84"65;
"CS1_A_N"
$PN"209"66;
"CS1_B_N"
$PN"229"67;
"DQ30_A"
$PN"192"68;
"DQ29_A"
$PN"49"69;
"DQ28_A"
$PN"47"70;
"DQ27_A"
$PN"187"71;
"DQ26_A"
$PN"185"72;
"DQ25_A"
$PN"42"73;
"DQ24_A"
$PN"40"74;
"DQ23_A"
$PN"183"75;
"DQ22_A"
$PN"181"76;
"DQ21_A"
$PN"38"77;
"DQ20_A"
$PN"36"78;
"DQ19_A"
$PN"176"79;
"DQ18_A"
$PN"174"80;
"DQ17_A"
$PN"31"81;
"DQ16_A"
$PN"29"82;
"DQ15_A"
$PN"172"83;
"DQ14_A"
$PN"170"84;
"DQ13_A"
$PN"27"85;
"DQ12_A"
$PN"25"86;
"DQ11_A"
$PN"165"87;
"DQ10_A"
$PN"163"88;
"DQ9_A"
$PN"20"89;
"DQ8_A"
$PN"18"90;
"DQ7_A"
$PN"161"91;
"DQ6_A"
$PN"159"92;
"DQ5_A"
$PN"16"93;
"DQ4_A"
$PN"14"94;
"DQ3_A"
$PN"154"95;
"DQ2_A"
$PN"152"96;
"DQ1_A"
$PN"9"97;
"DQ0_A"
$PN"7"98;
"DQ31_B"
$PN"287"99;
"DQ30_B"
$PN"285"100;
"DQ29_B"
$PN"142"101;
"DQ28_B"
$PN"140"102;
"DQ27_B"
$PN"280"103;
"DQ26_B"
$PN"278"104;
"DQ25_B"
$PN"135"105;
"DQ24_B"
$PN"133"106;
"DQ23_B"
$PN"276"107;
"DQ22_B"
$PN"274"108;
"DQ21_B"
$PN"131"109;
"DQ20_B"
$PN"129"110;
"DQ19_B"
$PN"269"111;
"DQ18_B"
$PN"267"112;
"DQ17_B"
$PN"124"113;
"DQ16_B"
$PN"122"114;
"DQ15_B"
$PN"265"26;
"DQ14_B"
$PN"263"27;
"DQ13_B"
$PN"120"115;
"DQ12_B"
$PN"118"116;
"DQ11_B"
$PN"258"117;
"DQ10_B"
$PN"256"118;
"DQ9_B"
$PN"113"119;
"DQ8_B"
$PN"111"120;
"DQ7_B"
$PN"254"121;
"DQ6_B"
$PN"252"122;
"DQ5_B"
$PN"109"123;
"DQ4_B"
$PN"107"124;
"DQ3_B"
$PN"247"125;
"DQ2_B"
$PN"245"126;
"DQ1_B"
$PN"102"127;
"DQ0_B"
$PN"100"128;
"HAS"
$PN"148"19;
"HSCL"
$PN"4"24;
"HSDA"
$PN"5"17;
"LBD||RSP_A_N"
$PN"86"129;
"LBS||RSP_B_N"
$PN"87"130;
"PAR_A"
$PN"74"131;
"PAR_B"
$PN"227"132;
"RESET_N \B"
$PN"207"20;
"RFU6"
$PN"232"0;
"RFU5"
$PN"231"0;
"RFU4"
$PN"220"0;
"RFU3"
$PN"150"0;
"RFU2"
$PN"149"0;
"RFU1"
$PN"144"0;
"RFU0"
$PN"2"0;
"VIN_MGMT"
$PN"3"18;
%"TAP"
"1","(-3250,3375)","0","mstr_standard","I220";
;
CDS_LIB"mstr_standard"
BODY_TYPE"PLUMBING"
HDL_TAP"TRUE";
"B \NAC \NWC"8;
"S \NAC"
BN"9"172;
%"TAP"
"1","(-3250,3275)","0","mstr_standard","I221";
;
CDS_LIB"mstr_standard"
BODY_TYPE"PLUMBING"
HDL_TAP"TRUE";
"B \NAC \NWC"8;
"S \NAC"
BN"8"135;
%"TAP"
"1","(-3050,3125)","0","mstr_standard","I222";
;
CDS_LIB"mstr_standard"
BODY_TYPE"PLUMBING"
HDL_TAP"TRUE";
"B \NAC \NWC"9;
"S \NAC"
BN"7"166;
%"TAP"
"1","(-3050,3025)","0","mstr_standard","I223";
;
CDS_LIB"mstr_standard"
BODY_TYPE"PLUMBING"
HDL_TAP"TRUE";
"B \NAC \NWC"9;
"S \NAC"
BN"6"163;
%"TAP"
"1","(-3050,2925)","0","mstr_standard","I224";
;
CDS_LIB"mstr_standard"
BODY_TYPE"PLUMBING"
HDL_TAP"TRUE";
"B \NAC \NWC"9;
"S \NAC"
BN"5"160;
%"TAP"
"1","(-3050,2825)","0","mstr_standard","I225";
;
CDS_LIB"mstr_standard"
BODY_TYPE"PLUMBING"
HDL_TAP"TRUE";
"B \NAC \NWC"9;
"S \NAC"
BN"4"156;
%"TAP"
"1","(-3050,2725)","0","mstr_standard","I226";
;
CDS_LIB"mstr_standard"
BODY_TYPE"PLUMBING"
HDL_TAP"TRUE";
"B \NAC \NWC"9;
"S \NAC"
BN"3"152;
%"TAP"
"1","(-3250,3175)","0","mstr_standard","I227";
;
CDS_LIB"mstr_standard"
BODY_TYPE"PLUMBING"
HDL_TAP"TRUE";
"B \NAC \NWC"8;
"S \NAC"
BN"7"137;
%"TAP"
"1","(-3250,3075)","0","mstr_standard","I228";
;
CDS_LIB"mstr_standard"
BODY_TYPE"PLUMBING"
HDL_TAP"TRUE";
"B \NAC \NWC"8;
"S \NAC"
BN"6"164;
%"TAP"
"1","(-3250,2975)","0","mstr_standard","I229";
;
CDS_LIB"mstr_standard"
BODY_TYPE"PLUMBING"
HDL_TAP"TRUE";
"B \NAC \NWC"8;
"S \NAC"
BN"5"161;
%"TAP"
"1","(-7475,3200)","2","mstr_standard","I23";
;
CDS_LIB"mstr_standard"
BODY_TYPE"PLUMBING"
HDL_TAP"TRUE";
"B \NAC \NWC"14;
"S \NAC"
BN"1"23;
%"TAP"
"1","(-3250,2875)","0","mstr_standard","I230";
;
CDS_LIB"mstr_standard"
BODY_TYPE"PLUMBING"
HDL_TAP"TRUE";
"B \NAC \NWC"8;
"S \NAC"
BN"4"157;
%"TAP"
"1","(-3250,2775)","0","mstr_standard","I231";
;
CDS_LIB"mstr_standard"
BODY_TYPE"PLUMBING"
HDL_TAP"TRUE";
"B \NAC \NWC"8;
"S \NAC"
BN"3"153;
%"TAP"
"1","(-3050,2625)","0","mstr_standard","I232";
;
CDS_LIB"mstr_standard"
BODY_TYPE"PLUMBING"
HDL_TAP"TRUE";
"B \NAC \NWC"9;
"S \NAC"
BN"2"148;
%"TAP"
"1","(-3050,2525)","0","mstr_standard","I233";
;
CDS_LIB"mstr_standard"
BODY_TYPE"PLUMBING"
HDL_TAP"TRUE";
"B \NAC \NWC"9;
"S \NAC"
BN"1"144;
%"TAP"
"1","(-3050,2425)","0","mstr_standard","I234";
;
CDS_LIB"mstr_standard"
BODY_TYPE"PLUMBING"
HDL_TAP"TRUE";
"B \NAC \NWC"9;
"S \NAC"
BN"0"140;
%"TAP"
"1","(-3250,2675)","0","mstr_standard","I235";
;
CDS_LIB"mstr_standard"
BODY_TYPE"PLUMBING"
HDL_TAP"TRUE";
"B \NAC \NWC"8;
"S \NAC"
BN"2"149;
%"TAP"
"1","(-3250,2575)","0","mstr_standard","I236";
;
CDS_LIB"mstr_standard"
BODY_TYPE"PLUMBING"
HDL_TAP"TRUE";
"B \NAC \NWC"8;
"S \NAC"
BN"1"145;
%"TAP"
"1","(-3250,2475)","0","mstr_standard","I237";
;
CDS_LIB"mstr_standard"
BODY_TYPE"PLUMBING"
HDL_TAP"TRUE";
"B \NAC \NWC"8;
"S \NAC"
BN"0"141;
%"SCONN288_DDR506112002KQ"
"2","(-4250,3425)","0","pure_quanta","I238";
;
LOCATION"J102"
$SEC"2"
CDS_SEC"2"
PART_TYPE"SMLF"
MATERIAL"IO"
VALUE"SCONN288_DDR506112002KQ"
CDS_LIB"pure_quanta"
NEEDS_NO_SIZE"TRUE"
CDS_LMAN_SYM_OUTLINE"-600,1150,600,-1150"
PART_NUMBER"DFHST8FS479";
"DQS7_A_C||TDQS7_A_C \B"
$PN"178"133;
"DQS6_A_T||TDQS6_A_T"
$PN"168"134;
"DQS8_B_T||TDQS8_B_T"
$PN"283"135;
"DQS8_B_C||TDQS8_B_C \B"
$PN"282"136;
"DQS7_B_T||TDQS7_B_T"
$PN"272"137;
"DQS0_A_C \B"
$PN"12"138;
"DQS0_A_T"
$PN"11"139;
"DQS0_B_C \B"
$PN"105"140;
"DQS0_B_T"
$PN"104"141;
"DQS1_A_C \B"
$PN"23"142;
"DQS1_A_T"
$PN"22"143;
"DQS1_B_C \B"
$PN"116"144;
"DQS1_B_T"
$PN"115"145;
"DQS2_A_C \B"
$PN"34"146;
"DQS2_A_T"
$PN"33"147;
"DQS2_B_C \B"
$PN"127"148;
"DQS2_B_T"
$PN"126"149;
"DQS3_A_C \B"
$PN"45"150;
"DQS3_A_T"
$PN"44"151;
"DQS3_B_C \B"
$PN"138"152;
"DQS3_B_T"
$PN"137"153;
"DQS4_A_C \B"
$PN"56"154;
"DQS4_A_T"
$PN"55"155;
"DQS4_B_C \B"
$PN"238"156;
"DQS4_B_T"
$PN"239"157;
"DQS5_A_C||TDQS5_A_C||DQS5_A_T||TDQS5_A_T \B"
$PN"156"158;
"DQS5_A_T||TDQS5_A_T"
$PN"157"159;
"DQS5_B_C||TDQS5_B_C \B"
$PN"249"160;
"DQS5_B_T||TDQS5_B_T"
$PN"250"161;
"DQS6_A_C||TDQS6_A_C||DQS6_A_T||TDQS6_A_T \B"
$PN"167"162;
"DQS6_B_C||TDQS6_B_C \B"
$PN"260"163;
"DQS6_B_T||TDQS6_B_T"
$PN"261"164;
"DQS7_A_T||TDQS7_A_T"
$PN"179"165;
"DQS7_B_C||TDQS7_B_C \B"
$PN"271"166;
"DQS8_A_C||TDQS8_A_C \B"
$PN"189"167;
"DQS8_A_T||TDQS8_A_T"
$PN"190"168;
"DQS9_A_C||TDQS9_A_C \B"
$PN"200"169;
"DQS9_A_T||TDQS9_A_T"
$PN"201"170;
"DQS9_B_C||TDQS9_B_C \B"
$PN"94"171;
"DQS9_B_T||TDQS9_B_T||DBI4_B_N"
$PN"93"172;
%"GND"
"1","(-2825,5525)","0","pure_quanta_power","I239";
;
ROOM"MEM_EFGH_DECOUPLING_CAPS"
SIZE"1B"
BOM_COST"MEM"
CDS_LIB"pure_quanta_power"
HDL_POWER"GND";
"A<SIZE-1..0>\NAC"35;
%"TAP"
"1","(-7475,3150)","2","mstr_standard","I24";
;
CDS_LIB"mstr_standard"
BODY_TYPE"PLUMBING"
HDL_TAP"TRUE";
"B \NAC \NWC"14;
"S \NAC"
BN"0"22;
%"Q_CAP"
"1","(-2825,5875)","2","pure_quanta","I240";
;
LOCATION"C530"
$SEC"1"
CDS_SEC"1"
MATERIAL"X6S"
TOLERANCE"10%"
VOLTAGE"25V"
PACK_TYPE"C0805"
VALUE"10UF"
BOM_COST"MEM"
CDS_LIB"pure_quanta"
ROOM""
PART_NUMBER"CH6104KEA00";
"B"
$PN"2"35;
"A"
$PN"1"34;
%"Q_CAP"
"1","(-2250,5875)","2","pure_quanta","I241";
;
LOCATION"C531"
$SEC"1"
CDS_SEC"1"
TOLERANCE"10%"
VALUE"10UF"
VOLTAGE"25V"
PACK_TYPE"C0805"
MATERIAL"X6S"
BOM_COST"MEM"
CDS_LIB"pure_quanta"
ROOM""
PART_NUMBER"CH6104KEA00";
"B"
$PN"2"35;
"A"
$PN"1"34;
%"UNIVERSAL_POWER"
"1","(-2825,6200)","0","pure_quanta_power","I242";
;
HDL_POWER"P12V_MEM_CPU1"
CDS_LIB"pure_quanta_power";
"A"34;
%"Q_RES"
"1","(-7525,2575)","0","pure_quanta","I244";
;
LOCATION"R1586"
$SEC"1"
CDS_SEC"1"
VALUE"49.9"
MATERIAL"CHIP"
PACK_TYPE"0402LF"
WATTAGE"1/16W"
TOLERANCE"1%"
CDS_LIB"pure_quanta"
PART_NUMBER"CS04992FB07";
"B"
$PN"2"24;
"A"
$PN"1"180;
%"Q_RES"
"2","(-8975,1375)","0","pure_quanta","I245";
;
LOCATION"R8040"
$SEC"1"
CDS_SEC"1"
WATTAGE"1/16W"
MATERIAL"CHIP"
VALUE"10K"
PACK_TYPE"0402LF"
TOLERANCE"1%"
CDS_LIB"pure_quanta"
PART_NUMBER"CS31002FB08";
"A"
$PN"1"5;
"B"
$PN"2"29;
%"VCC_CORE"
"1","(-8975,1675)","0","pure_quanta_power","I246";
;
HDL_POWER"P3V3_AUX"
CDS_LIB"pure_quanta_power"
VOLTAGE"3.3"
ROOM"PVCCINFAON_CPU0_CTRL";
"A"5;
%"Q_RES"
"1","(-3850,750)","0","pure_quanta","I249";
;
LOCATION"R8089"
$SEC"1"
CDS_SEC"1"
MATERIAL"CHIP"
WATTAGE"1/16W"
PACK_TYPE"0402LF"
TOLERANCE"5%"
VALUE"0"
CDS_LIB"pure_quanta"
PART_NUMBER"CS00002JB13";
"B"
$PN"2"28;
"A"
$PN"1"31;
%"TAP"
"1","(-7475,3350)","2","mstr_standard","I25";
;
CDS_LIB"mstr_standard"
BODY_TYPE"PLUMBING"
HDL_TAP"TRUE";
"B \NAC \NWC"14;
"S \NAC"
BN"4"59;
%"VCC_CORE"
"1","(-4875,1425)","0","pure_quanta_power","I250";
;
HDL_POWER"P3V3_AUX"
CDS_LIB"pure_quanta_power"
VOLTAGE"3.3"
ROOM"PVCCINFAON_CPU0_CTRL";
"A"32;
%"Q_RES"
"1","(-4275,1225)","0","pure_quanta","I251";
;
LOCATION"R8091"
$SEC"1"
CDS_SEC"1"
MATERIAL"EMPTY"
PACK_TYPE"0402LF"
VALUE"10K"
TOLERANCE"1%"
WATTAGE"1/16W"
CDS_LIB"pure_quanta"
PART_NUMBER"CS31002FB08";
"B"
$PN"2"28;
"A"
$PN"1"32;
%"Q_RES"
"1","(-2425,750)","0","pure_quanta","I252";
;
LOCATION"R8090"
$SEC"1"
CDS_SEC"1"
WATTAGE"1/16W"
VALUE"0"
TOLERANCE"5%"
MATERIAL"CHIP"
PACK_TYPE"0402LF"
CDS_LIB"pure_quanta"
PART_NUMBER"CS00002JB13";
"B"
$PN"2"38;
"A"
$PN"1"28;
%"SCHOTTKY_12"
"1","(-2325,1200)","0","pure_quanta","I253";
;
LOCATION"D8006"
$SEC"1"
CDS_SEC"1"
MATERIAL"EMPTY"
PART_TYPE"SMLF"
VALUE"B0530WS7F"
CDS_LIB"pure_quanta"
CDS_LMAN_SYM_OUTLINE"-75,50,75,-50"
NEEDS_NO_SIZE"TRUE"
PART_NUMBER"BC000530Z41";
"C"
$PN"2"33;
"A"
$PN"1"28;
%"VCC_CORE"
"1","(-1650,1325)","0","pure_quanta_power","I255";
;
HDL_POWER"P3V3_AUX"
CDS_LIB"pure_quanta_power"
ROOM"PVCCINFAON_CPU0_CTRL"
VOLTAGE"3.3";
"A"33;
%"Q_RES"
"1","(-7900,2800)","0","pure_quanta","I256";
;
LOCATION"R1705"
$SEC"1"
CDS_SEC"1"
VALUE"10"
MATERIAL"CHIP"
PACK_TYPE"0402LF"
CDS_LIB"pure_quanta"
WATTAGE"1/16W"
TOLERANCE"1%"
PART_NUMBER"CS01002FB07";
"B"
$PN"2"17;
"A"
$PN"1"179;
%"TAP"
"1","(-7475,3300)","2","mstr_standard","I26";
;
CDS_LIB"mstr_standard"
BODY_TYPE"PLUMBING"
HDL_TAP"TRUE";
"B \NAC \NWC"14;
"S \NAC"
BN"3"60;
%"TAP"
"1","(-7475,3250)","2","mstr_standard","I27";
;
CDS_LIB"mstr_standard"
BODY_TYPE"PLUMBING"
HDL_TAP"TRUE";
"B \NAC \NWC"14;
"S \NAC"
BN"2"61;
%"TAP"
"1","(-7475,3400)","2","mstr_standard","I28";
;
CDS_LIB"mstr_standard"
BODY_TYPE"PLUMBING"
HDL_TAP"TRUE";
"B \NAC \NWC"14;
"S \NAC"
BN"5"58;
%"TAP"
"1","(-7475,3450)","2","mstr_standard","I29";
;
CDS_LIB"mstr_standard"
BODY_TYPE"PLUMBING"
HDL_TAP"TRUE";
"B \NAC \NWC"14;
"S \NAC"
BN"6"25;
%"TAP"
"1","(-7475,3650)","2","mstr_standard","I30";
;
CDS_LIB"mstr_standard"
BODY_TYPE"PLUMBING"
HDL_TAP"TRUE";
"B \NAC \NWC"6;
"S \NAC"
BN"1"41;
%"TAP"
"1","(-7475,3700)","2","mstr_standard","I31";
;
CDS_LIB"mstr_standard"
BODY_TYPE"PLUMBING"
HDL_TAP"TRUE";
"B \NAC \NWC"6;
"S \NAC"
BN"2"56;
%"TAP"
"1","(-7475,3500)","2","mstr_standard","I32";
;
CDS_LIB"mstr_standard"
BODY_TYPE"PLUMBING"
HDL_TAP"TRUE";
"B \NAC \NWC"14;
"S \NAC"
BN"7"42;
%"TAP"
"1","(-7475,3600)","2","mstr_standard","I33";
;
CDS_LIB"mstr_standard"
BODY_TYPE"PLUMBING"
HDL_TAP"TRUE";
"B \NAC \NWC"6;
"S \NAC"
BN"0"57;
%"TAP"
"1","(-7475,3750)","2","mstr_standard","I34";
;
CDS_LIB"mstr_standard"
BODY_TYPE"PLUMBING"
HDL_TAP"TRUE";
"B \NAC \NWC"6;
"S \NAC"
BN"3"55;
%"TAP"
"1","(-5775,2200)","0","mstr_standard","I42";
;
CDS_LIB"mstr_standard"
BODY_TYPE"PLUMBING"
HDL_TAP"TRUE";
"B \NAC \NWC"12;
"S \NAC"
BN"1"127;
%"TAP"
"1","(-5775,2150)","0","mstr_standard","I43";
;
CDS_LIB"mstr_standard"
BODY_TYPE"PLUMBING"
HDL_TAP"TRUE";
"B \NAC \NWC"12;
"S \NAC"
BN"0"128;
%"TAP"
"1","(-5775,2400)","0","mstr_standard","I44";
;
CDS_LIB"mstr_standard"
BODY_TYPE"PLUMBING"
HDL_TAP"TRUE";
"B \NAC \NWC"12;
"S \NAC"
BN"5"123;
%"TAP"
"1","(-5775,2450)","0","mstr_standard","I45";
;
CDS_LIB"mstr_standard"
BODY_TYPE"PLUMBING"
HDL_TAP"TRUE";
"B \NAC \NWC"12;
"S \NAC"
BN"6"122;
%"TAP"
"1","(-5775,2250)","0","mstr_standard","I46";
;
CDS_LIB"mstr_standard"
BODY_TYPE"PLUMBING"
HDL_TAP"TRUE";
"B \NAC \NWC"12;
"S \NAC"
BN"2"126;
%"TAP"
"1","(-5775,2300)","0","mstr_standard","I47";
;
CDS_LIB"mstr_standard"
BODY_TYPE"PLUMBING"
HDL_TAP"TRUE";
"B \NAC \NWC"12;
"S \NAC"
BN"3"125;
%"TAP"
"1","(-5775,2350)","0","mstr_standard","I48";
;
CDS_LIB"mstr_standard"
BODY_TYPE"PLUMBING"
HDL_TAP"TRUE";
"B \NAC \NWC"12;
"S \NAC"
BN"4"124;
%"TAP"
"1","(-5775,2650)","0","mstr_standard","I49";
;
CDS_LIB"mstr_standard"
BODY_TYPE"PLUMBING"
HDL_TAP"TRUE";
"B \NAC \NWC"12;
"S \NAC"
BN"10"118;
%"VCC_CORE"
"1","(-8575,3425)","0","mstr_symbols","I5";
;
HDL_POWER"P3V3_AUX"
ROOM"PVCCINFAON_CPU1_CTRL"
VOLTAGE"3.3"
CDS_LIB"mstr_symbols";
"A"18;
%"TAP"
"1","(-5775,2700)","0","mstr_standard","I50";
;
CDS_LIB"mstr_standard"
BODY_TYPE"PLUMBING"
HDL_TAP"TRUE";
"B \NAC \NWC"12;
"S \NAC"
BN"11"117;
%"TAP"
"1","(-5775,2500)","0","mstr_standard","I51";
;
CDS_LIB"mstr_standard"
BODY_TYPE"PLUMBING"
HDL_TAP"TRUE";
"B \NAC \NWC"12;
"S \NAC"
BN"7"121;
%"TAP"
"1","(-5775,2550)","0","mstr_standard","I52";
;
CDS_LIB"mstr_standard"
BODY_TYPE"PLUMBING"
HDL_TAP"TRUE";
"B \NAC \NWC"12;
"S \NAC"
BN"8"120;
%"TAP"
"1","(-5775,2600)","0","mstr_standard","I53";
;
CDS_LIB"mstr_standard"
BODY_TYPE"PLUMBING"
HDL_TAP"TRUE";
"B \NAC \NWC"12;
"S \NAC"
BN"9"119;
%"TAP"
"1","(-5775,2950)","0","mstr_standard","I54";
;
CDS_LIB"mstr_standard"
BODY_TYPE"PLUMBING"
HDL_TAP"TRUE";
"B \NAC \NWC"12;
"S \NAC"
BN"16"114;
%"TAP"
"1","(-5775,2900)","0","mstr_standard","I55";
;
CDS_LIB"mstr_standard"
BODY_TYPE"PLUMBING"
HDL_TAP"TRUE";
"B \NAC \NWC"12;
"S \NAC"
BN"15"26;
%"TAP"
"1","(-5775,3000)","0","mstr_standard","I56";
;
CDS_LIB"mstr_standard"
BODY_TYPE"PLUMBING"
HDL_TAP"TRUE";
"B \NAC \NWC"12;
"S \NAC"
BN"17"113;
%"TAP"
"1","(-5775,2750)","0","mstr_standard","I57";
;
CDS_LIB"mstr_standard"
BODY_TYPE"PLUMBING"
HDL_TAP"TRUE";
"B \NAC \NWC"12;
"S \NAC"
BN"12"116;
%"TAP"
"1","(-5775,2800)","0","mstr_standard","I58";
;
CDS_LIB"mstr_standard"
BODY_TYPE"PLUMBING"
HDL_TAP"TRUE";
"B \NAC \NWC"12;
"S \NAC"
BN"13"115;
%"TAP"
"1","(-5775,2850)","0","mstr_standard","I59";
;
CDS_LIB"mstr_standard"
BODY_TYPE"PLUMBING"
HDL_TAP"TRUE";
"B \NAC \NWC"12;
"S \NAC"
BN"14"27;
%"TAP"
"1","(-5775,3150)","0","mstr_standard","I60";
;
CDS_LIB"mstr_standard"
BODY_TYPE"PLUMBING"
HDL_TAP"TRUE";
"B \NAC \NWC"12;
"S \NAC"
BN"20"110;
%"TAP"
"1","(-5775,3200)","0","mstr_standard","I61";
;
CDS_LIB"mstr_standard"
BODY_TYPE"PLUMBING"
HDL_TAP"TRUE";
"B \NAC \NWC"12;
"S \NAC"
BN"21"109;
%"TAP"
"1","(-5775,3250)","0","mstr_standard","I62";
;
CDS_LIB"mstr_standard"
BODY_TYPE"PLUMBING"
HDL_TAP"TRUE";
"B \NAC \NWC"12;
"S \NAC"
BN"22"108;
%"TAP"
"1","(-5775,3050)","0","mstr_standard","I63";
;
CDS_LIB"mstr_standard"
BODY_TYPE"PLUMBING"
HDL_TAP"TRUE";
"B \NAC \NWC"12;
"S \NAC"
BN"18"112;
%"TAP"
"1","(-5775,3100)","0","mstr_standard","I64";
;
CDS_LIB"mstr_standard"
BODY_TYPE"PLUMBING"
HDL_TAP"TRUE";
"B \NAC \NWC"12;
"S \NAC"
BN"19"111;
%"TAP"
"1","(-5775,3400)","0","mstr_standard","I65";
;
CDS_LIB"mstr_standard"
BODY_TYPE"PLUMBING"
HDL_TAP"TRUE";
"B \NAC \NWC"12;
"S \NAC"
BN"25"105;
%"TAP"
"1","(-5775,3450)","0","mstr_standard","I66";
;
CDS_LIB"mstr_standard"
BODY_TYPE"PLUMBING"
HDL_TAP"TRUE";
"B \NAC \NWC"12;
"S \NAC"
BN"26"104;
%"TAP"
"1","(-5775,3500)","0","mstr_standard","I67";
;
CDS_LIB"mstr_standard"
BODY_TYPE"PLUMBING"
HDL_TAP"TRUE";
"B \NAC \NWC"12;
"S \NAC"
BN"27"103;
%"TAP"
"1","(-5775,3300)","0","mstr_standard","I68";
;
CDS_LIB"mstr_standard"
BODY_TYPE"PLUMBING"
HDL_TAP"TRUE";
"B \NAC \NWC"12;
"S \NAC"
BN"23"107;
%"TAP"
"1","(-5775,3350)","0","mstr_standard","I69";
;
CDS_LIB"mstr_standard"
BODY_TYPE"PLUMBING"
HDL_TAP"TRUE";
"B \NAC \NWC"12;
"S \NAC"
BN"24"106;
%"TAP"
"1","(-5775,3650)","0","mstr_standard","I70";
;
CDS_LIB"mstr_standard"
BODY_TYPE"PLUMBING"
HDL_TAP"TRUE";
"B \NAC \NWC"12;
"S \NAC"
BN"30"100;
%"TAP"
"1","(-5775,3700)","0","mstr_standard","I71";
;
CDS_LIB"mstr_standard"
BODY_TYPE"PLUMBING"
HDL_TAP"TRUE";
"B \NAC \NWC"12;
"S \NAC"
BN"31"99;
%"TAP"
"1","(-5775,3550)","0","mstr_standard","I72";
;
CDS_LIB"mstr_standard"
BODY_TYPE"PLUMBING"
HDL_TAP"TRUE";
"B \NAC \NWC"12;
"S \NAC"
BN"28"102;
%"TAP"
"1","(-5775,3600)","0","mstr_standard","I73";
;
CDS_LIB"mstr_standard"
BODY_TYPE"PLUMBING"
HDL_TAP"TRUE";
"B \NAC \NWC"12;
"S \NAC"
BN"29"101;
%"TAP"
"1","(-7475,3800)","2","mstr_standard","I76";
;
CDS_LIB"mstr_standard"
BODY_TYPE"PLUMBING"
HDL_TAP"TRUE";
"B \NAC \NWC"6;
"S \NAC"
BN"4"40;
%"TAP"
"1","(-7475,3850)","2","mstr_standard","I77";
;
CDS_LIB"mstr_standard"
BODY_TYPE"PLUMBING"
HDL_TAP"TRUE";
"B \NAC \NWC"6;
"S \NAC"
BN"5"54;
%"TAP"
"1","(-7475,3900)","2","mstr_standard","I78";
;
CDS_LIB"mstr_standard"
BODY_TYPE"PLUMBING"
HDL_TAP"TRUE";
"B \NAC \NWC"6;
"S \NAC"
BN"6"53;
%"TAP"
"1","(-7475,3950)","2","mstr_standard","I79";
;
CDS_LIB"mstr_standard"
BODY_TYPE"PLUMBING"
HDL_TAP"TRUE";
"B \NAC \NWC"6;
"S \NAC"
BN"7"177;
%"TAP"
"1","(-7475,4750)","2","mstr_standard","I80";
;
CDS_LIB"mstr_standard"
BODY_TYPE"PLUMBING"
HDL_TAP"TRUE";
"B \NAC \NWC"15;
"S \NAC"
BN"2"45;
%"TAP"
"1","(-7475,4700)","2","mstr_standard","I81";
;
CDS_LIB"mstr_standard"
BODY_TYPE"PLUMBING"
HDL_TAP"TRUE";
"B \NAC \NWC"15;
"S \NAC"
BN"1"44;
%"TAP"
"1","(-7475,4650)","2","mstr_standard","I82";
;
CDS_LIB"mstr_standard"
BODY_TYPE"PLUMBING"
HDL_TAP"TRUE";
"B \NAC \NWC"15;
"S \NAC"
BN"0"43;
%"TAP"
"1","(-7475,4850)","2","mstr_standard","I83";
;
CDS_LIB"mstr_standard"
BODY_TYPE"PLUMBING"
HDL_TAP"TRUE";
"B \NAC \NWC"15;
"S \NAC"
BN"4"48;
%"TAP"
"1","(-7475,4800)","2","mstr_standard","I84";
;
CDS_LIB"mstr_standard"
BODY_TYPE"PLUMBING"
HDL_TAP"TRUE";
"B \NAC \NWC"15;
"S \NAC"
BN"3"46;
%"TAP"
"1","(-7475,4950)","2","mstr_standard","I85";
;
CDS_LIB"mstr_standard"
BODY_TYPE"PLUMBING"
HDL_TAP"TRUE";
"B \NAC \NWC"15;
"S \NAC"
BN"6"52;
%"TAP"
"1","(-7475,4900)","2","mstr_standard","I86";
;
CDS_LIB"mstr_standard"
BODY_TYPE"PLUMBING"
HDL_TAP"TRUE";
"B \NAC \NWC"15;
"S \NAC"
BN"5"50;
%"TAP"
"1","(-7475,5050)","2","mstr_standard","I87";
;
CDS_LIB"mstr_standard"
BODY_TYPE"PLUMBING"
HDL_TAP"TRUE";
"B \NAC \NWC"7;
"S \NAC"
BN"0"173;
%"TAP"
"1","(-7475,5150)","2","mstr_standard","I88";
;
CDS_LIB"mstr_standard"
BODY_TYPE"PLUMBING"
HDL_TAP"TRUE";
"B \NAC \NWC"7;
"S \NAC"
BN"2"175;
%"TAP"
"1","(-7475,5100)","2","mstr_standard","I89";
;
CDS_LIB"mstr_standard"
BODY_TYPE"PLUMBING"
HDL_TAP"TRUE";
"B \NAC \NWC"7;
"S \NAC"
BN"1"174;
%"TAP"
"1","(-7475,5200)","2","mstr_standard","I90";
;
CDS_LIB"mstr_standard"
BODY_TYPE"PLUMBING"
HDL_TAP"TRUE";
"B \NAC \NWC"7;
"S \NAC"
BN"3"176;
%"TAP"
"1","(-7475,5250)","2","mstr_standard","I91";
;
CDS_LIB"mstr_standard"
BODY_TYPE"PLUMBING"
HDL_TAP"TRUE";
"B \NAC \NWC"7;
"S \NAC"
BN"4"47;
%"TAP"
"1","(-7475,5300)","2","mstr_standard","I92";
;
CDS_LIB"mstr_standard"
BODY_TYPE"PLUMBING"
HDL_TAP"TRUE";
"B \NAC \NWC"7;
"S \NAC"
BN"5"49;
%"TAP"
"1","(-7475,5350)","2","mstr_standard","I93";
;
CDS_LIB"mstr_standard"
BODY_TYPE"PLUMBING"
HDL_TAP"TRUE";
"B \NAC \NWC"7;
"S \NAC"
BN"6"51;
%"TAP"
"1","(-5775,4000)","0","mstr_standard","I94";
;
CDS_LIB"mstr_standard"
BODY_TYPE"PLUMBING"
HDL_TAP"TRUE";
"B \NAC \NWC"13;
"S \NAC"
BN"4"94;
%"TAP"
"1","(-5775,3900)","0","mstr_standard","I95";
;
CDS_LIB"mstr_standard"
BODY_TYPE"PLUMBING"
HDL_TAP"TRUE";
"B \NAC \NWC"13;
"S \NAC"
BN"2"96;
%"TAP"
"1","(-5775,3950)","0","mstr_standard","I96";
;
CDS_LIB"mstr_standard"
BODY_TYPE"PLUMBING"
HDL_TAP"TRUE";
"B \NAC \NWC"13;
"S \NAC"
BN"3"95;
%"TAP"
"1","(-5775,3800)","0","mstr_standard","I97";
;
CDS_LIB"mstr_standard"
BODY_TYPE"PLUMBING"
HDL_TAP"TRUE";
"B \NAC \NWC"13;
"S \NAC"
BN"0"98;
%"TAP"
"1","(-5775,3850)","0","mstr_standard","I98";
;
CDS_LIB"mstr_standard"
BODY_TYPE"PLUMBING"
HDL_TAP"TRUE";
"B \NAC \NWC"13;
"S \NAC"
BN"1"97;
%"TAP"
"1","(-5775,4150)","0","mstr_standard","I99";
;
CDS_LIB"mstr_standard"
BODY_TYPE"PLUMBING"
HDL_TAP"TRUE";
"B \NAC \NWC"13;
"S \NAC"
BN"7"91;
END.
